(kicad_pcb
	(version 20260206)
	(generator "pcbnew")
	(generator_version "10.0")
	(general
		(thickness 1.6)
		(legacy_teardrops no)
	)
	(paper "A4")
	(title_block
		(title "03242023_DA0F0TMBIJ0_F0T_Motherboard_J_brd_V01_OCP.brd")
		(comment 1 "Grand Teton / footprints 1787-1791 of 6105")
	)
	(layers
		(0 "F.Cu" signal "TOP")
		(4 "In1.Cu" signal "GND")
		(6 "In2.Cu" signal "IN1")
		(8 "In3.Cu" signal "GND1")
		(10 "In4.Cu" signal "IN2")
		(12 "In5.Cu" signal "GND2")
		(14 "In6.Cu" signal "IN3")
		(16 "In7.Cu" signal "GND3")
		(18 "In8.Cu" signal "VCC")
		(20 "In9.Cu" signal "VCC1")
		(22 "In10.Cu" signal "GND4")
		(24 "In11.Cu" signal "IN4")
		(26 "In12.Cu" signal "GND5")
		(28 "In13.Cu" signal "IN5")
		(30 "In14.Cu" signal "GND6")
		(32 "In15.Cu" signal "IN6")
		(34 "In16.Cu" signal "GND7")
		(2 "B.Cu" signal "BOTTOM")
		(9 "F.Adhes" user "F.Adhesive")
		(11 "B.Adhes" user "B.Adhesive")
		(13 "F.Paste" user "Package Geometry/Pastemask Top")
		(15 "B.Paste" user "Package Geometry/Pastemask Bottom")
		(5 "F.SilkS" user "Ref Des/Silkscreen Top")
		(7 "B.SilkS" user "Ref Des/Silkscreen Bottom")
		(1 "F.Mask" user "Board Geometry/Soldermask Top")
		(3 "B.Mask" user "Board Geometry/Soldermask Bottom")
		(17 "Dwgs.User" user "User.Drawings")
		(19 "Cmts.User" user "User.Comments")
		(21 "Eco1.User" user "User.Eco1")
		(23 "Eco2.User" user "User.Eco2")
		(25 "Edge.Cuts" user "Board Geometry/Outline")
		(27 "Margin" user)
		(31 "F.CrtYd" user "Package Geometry/Place Bound Top")
		(29 "B.CrtYd" user "Package Geometry/Place Bound Bottom")
		(35 "F.Fab" user "Ref Des/Assembly Top")
		(33 "B.Fab" user "Ref Des/Assembly Bottom")
	)
	(footprint ""
		(layer "F.Cu")
		(at 194.853306 -399.743422 180)
		(property "Reference" "PC2347"
			(at 0 0 180)
			(layer "F.SilkS")
			(hide yes)
			(effects
				(font
					(size 1.27 1.27)
				)
			)
		)
		(property "Value" ""
			(at 0 0 180)
			(layer "F.Fab")
			(effects
				(font
					(size 1.27 1.27)
				)
			)
		)
		(duplicate_pad_numbers_are_jumpers no)
		(fp_line
			(start 0.7874 0.4064)
			(end -0.7874 0.4064)
			(stroke
				(width 0.1524)
				(type default)
			)
			(layer "F.SilkS")
		)
		(fp_line
			(start 0.7874 -0.4064)
			(end 0.7874 0.4064)
			(stroke
				(width 0.1524)
				(type default)
			)
			(layer "F.SilkS")
		)
		(fp_line
			(start -0.7874 0.4064)
			(end -0.7874 -0.4064)
			(stroke
				(width 0.1524)
				(type default)
			)
			(layer "F.SilkS")
		)
		(fp_line
			(start -0.7874 -0.4064)
			(end 0.7874 -0.4064)
			(stroke
				(width 0.1524)
				(type default)
			)
			(layer "F.SilkS")
		)
		(fp_line
			(start 0.67945 0.3048)
			(end 0.120396 0.3048)
			(stroke
				(width 0.1)
				(type default)
			)
			(layer "F.Fab")
		)
		(fp_line
			(start 0.67945 -0.3048)
			(end 0.67945 0.3048)
			(stroke
				(width 0.1)
				(type default)
			)
			(layer "F.Fab")
		)
		(fp_line
			(start 0.12065 -0.2794)
			(end 0.12065 -0.3048)
			(stroke
				(width 0.1)
				(type default)
			)
			(layer "F.Fab")
		)
		(fp_line
			(start 0.12065 -0.3048)
			(end 0.67945 -0.3048)
			(stroke
				(width 0.1)
				(type default)
			)
			(layer "F.Fab")
		)
		(fp_line
			(start 0.120396 0.3048)
			(end 0.120396 0.2794)
			(stroke
				(width 0.1)
				(type default)
			)
			(layer "F.Fab")
		)
		(fp_line
			(start 0.120396 0.2794)
			(end -0.12065 0.2794)
			(stroke
				(width 0.1)
				(type default)
			)
			(layer "F.Fab")
		)
		(fp_line
			(start -0.12065 0.3048)
			(end -0.67945 0.3048)
			(stroke
				(width 0.1)
				(type default)
			)
			(layer "F.Fab")
		)
		(fp_line
			(start -0.12065 0.2794)
			(end -0.12065 0.3048)
			(stroke
				(width 0.1)
				(type default)
			)
			(layer "F.Fab")
		)
		(fp_line
			(start -0.12065 -0.2794)
			(end 0.12065 -0.2794)
			(stroke
				(width 0.1)
				(type default)
			)
			(layer "F.Fab")
		)
		(fp_line
			(start -0.12065 -0.305054)
			(end -0.12065 -0.2794)
			(stroke
				(width 0.1)
				(type default)
			)
			(layer "F.Fab")
		)
		(fp_line
			(start -0.67945 0.3048)
			(end -0.67945 -0.305054)
			(stroke
				(width 0.1)
				(type default)
			)
			(layer "F.Fab")
		)
		(fp_line
			(start -0.67945 -0.305054)
			(end -0.12065 -0.305054)
			(stroke
				(width 0.1)
				(type default)
			)
			(layer "F.Fab")
		)
		(pad "1" smd circle
			(at -0.40005 0 180)
			(size 0 0)
			(layers "F.Cu" "F.Mask" "F.Paste")
			(net "HSC_OCREF")
		)
		(pad "2" smd circle
			(at 0.40005 0 180)
			(size 0 0)
			(layers "F.Cu" "F.Mask" "F.Paste")
			(net "AGND_HSC")
		)
	)
	(footprint ""
		(layer "F.Cu")
		(at 129.46888 -100.167948 90)
		(property "Reference" "R205"
			(at 0 0 90)
			(layer "F.SilkS")
			(hide yes)
			(effects
				(font
					(size 1.27 1.27)
				)
			)
		)
		(property "Value" ""
			(at 0 0 90)
			(layer "F.Fab")
			(effects
				(font
					(size 1.27 1.27)
				)
			)
		)
		(duplicate_pad_numbers_are_jumpers no)
		(fp_line
			(start 0.7874 -0.4064)
			(end 0.7874 0.4064)
			(stroke
				(width 0.1524)
				(type default)
			)
			(layer "F.SilkS")
		)
		(fp_line
			(start -0.7874 -0.4064)
			(end 0.7874 -0.4064)
			(stroke
				(width 0.1524)
				(type default)
			)
			(layer "F.SilkS")
		)
		(fp_line
			(start 0.7874 0.4064)
			(end -0.7874 0.4064)
			(stroke
				(width 0.1524)
				(type default)
			)
			(layer "F.SilkS")
		)
		(fp_line
			(start -0.7874 0.4064)
			(end -0.7874 -0.4064)
			(stroke
				(width 0.1524)
				(type default)
			)
			(layer "F.SilkS")
		)
		(fp_line
			(start -0.12065 -0.305054)
			(end -0.12065 -0.2794)
			(stroke
				(width 0.1)
				(type default)
			)
			(layer "F.Fab")
		)
		(fp_line
			(start -0.67945 -0.305054)
			(end -0.12065 -0.305054)
			(stroke
				(width 0.1)
				(type default)
			)
			(layer "F.Fab")
		)
		(fp_line
			(start 0.67945 -0.3048)
			(end 0.67945 0.3048)
			(stroke
				(width 0.1)
				(type default)
			)
			(layer "F.Fab")
		)
		(fp_line
			(start 0.12065 -0.3048)
			(end 0.67945 -0.3048)
			(stroke
				(width 0.1)
				(type default)
			)
			(layer "F.Fab")
		)
		(fp_line
			(start 0.12065 -0.2794)
			(end 0.12065 -0.3048)
			(stroke
				(width 0.1)
				(type default)
			)
			(layer "F.Fab")
		)
		(fp_line
			(start -0.12065 -0.2794)
			(end 0.12065 -0.2794)
			(stroke
				(width 0.1)
				(type default)
			)
			(layer "F.Fab")
		)
		(fp_line
			(start 0.120396 0.2794)
			(end -0.12065 0.2794)
			(stroke
				(width 0.1)
				(type default)
			)
			(layer "F.Fab")
		)
		(fp_line
			(start -0.12065 0.2794)
			(end -0.12065 0.3048)
			(stroke
				(width 0.1)
				(type default)
			)
			(layer "F.Fab")
		)
		(fp_line
			(start 0.67945 0.3048)
			(end 0.120396 0.3048)
			(stroke
				(width 0.1)
				(type default)
			)
			(layer "F.Fab")
		)
		(fp_line
			(start 0.120396 0.3048)
			(end 0.120396 0.2794)
			(stroke
				(width 0.1)
				(type default)
			)
			(layer "F.Fab")
		)
		(fp_line
			(start -0.12065 0.3048)
			(end -0.67945 0.3048)
			(stroke
				(width 0.1)
				(type default)
			)
			(layer "F.Fab")
		)
		(fp_line
			(start -0.67945 0.3048)
			(end -0.67945 -0.305054)
			(stroke
				(width 0.1)
				(type default)
			)
			(layer "F.Fab")
		)
		(pad "1" smd circle
			(at -0.40005 0 90)
			(size 0 0)
			(layers "F.Cu" "F.Mask" "F.Paste")
			(net "H_CPU0_MEMTRIP_LVC1_R_N")
		)
		(pad "2" smd circle
			(at 0.40005 0 90)
			(size 0 0)
			(layers "F.Cu" "F.Mask" "F.Paste")
			(net "H_CPU0_MEMTRIP_OUT_VT_R_N")
		)
	)
	(footprint ""
		(layer "F.Cu")
		(at 274.72894 -96.329754 180)
		(property "Reference" "R722"
			(at 0 0 180)
			(layer "F.SilkS")
			(hide yes)
			(effects
				(font
					(size 1.27 1.27)
				)
			)
		)
		(property "Value" ""
			(at 0 0 180)
			(layer "F.Fab")
			(effects
				(font
					(size 1.27 1.27)
				)
			)
		)
		(duplicate_pad_numbers_are_jumpers no)
		(fp_line
			(start 0.7874 0.4064)
			(end -0.7874 0.4064)
			(stroke
				(width 0.1524)
				(type default)
			)
			(layer "F.SilkS")
		)
		(fp_line
			(start 0.7874 -0.4064)
			(end 0.7874 0.4064)
			(stroke
				(width 0.1524)
				(type default)
			)
			(layer "F.SilkS")
		)
		(fp_line
			(start -0.7874 0.4064)
			(end -0.7874 -0.4064)
			(stroke
				(width 0.1524)
				(type default)
			)
			(layer "F.SilkS")
		)
		(fp_line
			(start -0.7874 -0.4064)
			(end 0.7874 -0.4064)
			(stroke
				(width 0.1524)
				(type default)
			)
			(layer "F.SilkS")
		)
		(fp_line
			(start 0.67945 0.3048)
			(end 0.120396 0.3048)
			(stroke
				(width 0.1)
				(type default)
			)
			(layer "F.Fab")
		)
		(fp_line
			(start 0.67945 -0.3048)
			(end 0.67945 0.3048)
			(stroke
				(width 0.1)
				(type default)
			)
			(layer "F.Fab")
		)
		(fp_line
			(start 0.12065 -0.2794)
			(end 0.12065 -0.3048)
			(stroke
				(width 0.1)
				(type default)
			)
			(layer "F.Fab")
		)
		(fp_line
			(start 0.12065 -0.3048)
			(end 0.67945 -0.3048)
			(stroke
				(width 0.1)
				(type default)
			)
			(layer "F.Fab")
		)
		(fp_line
			(start 0.120396 0.3048)
			(end 0.120396 0.2794)
			(stroke
				(width 0.1)
				(type default)
			)
			(layer "F.Fab")
		)
		(fp_line
			(start 0.120396 0.2794)
			(end -0.12065 0.2794)
			(stroke
				(width 0.1)
				(type default)
			)
			(layer "F.Fab")
		)
		(fp_line
			(start -0.12065 0.3048)
			(end -0.67945 0.3048)
			(stroke
				(width 0.1)
				(type default)
			)
			(layer "F.Fab")
		)
		(fp_line
			(start -0.12065 0.2794)
			(end -0.12065 0.3048)
			(stroke
				(width 0.1)
				(type default)
			)
			(layer "F.Fab")
		)
		(fp_line
			(start -0.12065 -0.2794)
			(end 0.12065 -0.2794)
			(stroke
				(width 0.1)
				(type default)
			)
			(layer "F.Fab")
		)
		(fp_line
			(start -0.12065 -0.305054)
			(end -0.12065 -0.2794)
			(stroke
				(width 0.1)
				(type default)
			)
			(layer "F.Fab")
		)
		(fp_line
			(start -0.67945 0.3048)
			(end -0.67945 -0.305054)
			(stroke
				(width 0.1)
				(type default)
			)
			(layer "F.Fab")
		)
		(fp_line
			(start -0.67945 -0.305054)
			(end -0.12065 -0.305054)
			(stroke
				(width 0.1)
				(type default)
			)
			(layer "F.Fab")
		)
		(pad "1" smd circle
			(at -0.40005 0 180)
			(size 0 0)
			(layers "F.Cu" "F.Mask" "F.Paste")
			(net "MB_FRU_ADDR0")
		)
		(pad "2" smd circle
			(at 0.40005 0 180)
			(size 0 0)
			(layers "F.Cu" "F.Mask" "F.Paste")
			(net "GND")
		)
	)
	(footprint ""
		(layer "F.Cu")
		(at 362.89488 -296.05478)
		(property "Reference" "C213"
			(at 0 0 0)
			(layer "F.SilkS")
			(hide yes)
			(effects
				(font
					(size 1.27 1.27)
				)
			)
		)
		(property "Value" ""
			(at 0 0 0)
			(layer "F.Fab")
			(effects
				(font
					(size 1.27 1.27)
				)
			)
		)
		(duplicate_pad_numbers_are_jumpers no)
		(fp_line
			(start -1.524 -0.762)
			(end 1.524 -0.762)
			(stroke
				(width 0.1524)
				(type default)
			)
			(layer "F.SilkS")
		)
		(fp_line
			(start -1.524 0.762)
			(end -1.524 -0.762)
			(stroke
				(width 0.1524)
				(type default)
			)
			(layer "F.SilkS")
		)
		(fp_line
			(start 1.524 -0.762)
			(end 1.524 0.762)
			(stroke
				(width 0.1524)
				(type default)
			)
			(layer "F.SilkS")
		)
		(fp_line
			(start 1.524 0.762)
			(end -1.524 0.762)
			(stroke
				(width 0.1524)
				(type default)
			)
			(layer "F.SilkS")
		)
		(fp_line
			(start -1.1049 -0.724916)
			(end -1.1049 0.724916)
			(stroke
				(width 0.1)
				(type default)
			)
			(layer "F.Fab")
		)
		(fp_line
			(start -1.1049 0.724916)
			(end 1.1049 0.724916)
			(stroke
				(width 0.1)
				(type default)
			)
			(layer "F.Fab")
		)
		(fp_line
			(start 1.1049 -0.724916)
			(end -1.1049 -0.724916)
			(stroke
				(width 0.1)
				(type default)
			)
			(layer "F.Fab")
		)
		(fp_line
			(start 1.1049 0.724916)
			(end 1.1049 -0.724916)
			(stroke
				(width 0.1)
				(type default)
			)
			(layer "F.Fab")
		)
		(pad "1" smd rect
			(at -0.889 0 180)
			(size 1.016 1.27)
			(layers "F.Cu" "F.Mask" "F.Paste")
			(net "PVCCIN_CPU0")
		)
		(pad "2" smd rect
			(at 0.889 0 180)
			(size 1.016 1.27)
			(layers "F.Cu" "F.Mask" "F.Paste")
			(net "GND")
		)
	)
	(footprint ""
		(layer "F.Cu")
		(at 356.899972 -28.450032)
		(property "Reference" "H36"
			(at 3.200908 -2.585466 0)
			(unlocked yes)
			(layer "F.SilkS")
			(effects
				(font
					(size 0.7874 0.5842)
					(thickness 0.1524)
				)
				(justify left)
			)
		)
		(property "Value" ""
			(at 0 0 0)
			(layer "F.Fab")
			(effects
				(font
					(size 1.27 1.27)
				)
			)
		)
		(duplicate_pad_numbers_are_jumpers no)
		(fp_circle
			(center 0 0)
			(end 2.3622 0)
			(stroke
				(width 0.1524)
				(type default)
			)
			(fill no)
			(layer "F.SilkS")
		)
		(fp_circle
			(center 0 0)
			(end 2.3622 0)
			(stroke
				(width 0.1524)
				(type default)
			)
			(fill no)
			(layer "B.SilkS")
		)
		(fp_circle
			(center 0 0)
			(end 2.3622 0)
			(stroke
				(width 0.1)
				(type default)
			)
			(fill no)
			(layer "B.Fab")
		)
		(fp_circle
			(center 0 0)
			(end 2.3622 0)
			(stroke
				(width 0.1)
				(type default)
			)
			(fill no)
			(layer "F.Fab")
		)
		(pad "" np_thru_hole circle
			(at 0 0)
			(size 3.0988 3.0988)
			(drill 3.0988)
			(layers "*.Cu" "*.Mask")
			(clearance 0.254)
			(thermal_gap 0.254)
		)
	)
)
